# T6G (Grand Teton) — schematic netlist excerpt (pin names and nets, part order shuffled) for the footprints in the layout excerpt that follows; sources: Cadence DE-HDL packaged netlist, KiCad conversion of 04192023_DAF0TMB3IC0_F0TG_MB_C_brd_V02_OCP.brd

R3448  Q_RES  4.7K 5% EMPTY  pkg 0402LF  page 128 : A = P3V3_AUX ; B = GPU_FPGA_BOOT_EN
R876  Q_RES  10K 1% CHIP  pkg 0201LF  page 342 : A = GPIO3_RT_CPU1_P2 ; B = GND
C6700  Q_CAP_DIFFBUS  DIFF BUS_0.22UF 6.3V 20% X6S  pkg C0201  page 341 : \1\ = P5E_CPU1_P2_TX_BUF_C_DN<3> ; \2\ = P5E_CPU1_P2_TX_BUF_DN<3>

(kicad_pcb
	(version 20260206)
	(generator "pcbnew")
	(generator_version "10.0")
	(general
		(thickness 1.6)
		(legacy_teardrops no)
	)
	(paper "A4")
	(title_block
		(title "04192023_DAF0TMB3IC0_F0TG_MB_C_brd_V02_OCP.brd")
		(comment 1 "Grand Teton / footprints 3866-3868 of 8354")
	)
	(layers
		(0 "F.Cu" signal "TOP")
		(4 "In1.Cu" signal "GND")
		(6 "In2.Cu" signal "IN1")
		(8 "In3.Cu" signal "GND1")
		(10 "In4.Cu" signal "IN2")
		(12 "In5.Cu" signal "GND2")
		(14 "In6.Cu" signal "IN3")
		(16 "In7.Cu" signal "GND3")
		(18 "In8.Cu" signal "VCC")
		(20 "In9.Cu" signal "VCC1")
		(22 "In10.Cu" signal "GND4")
		(24 "In11.Cu" signal "IN4")
		(26 "In12.Cu" signal "GND5")
		(28 "In13.Cu" signal "IN5")
		(30 "In14.Cu" signal "GND6")
		(32 "In15.Cu" signal "IN6")
		(34 "In16.Cu" signal "GND7")
		(2 "B.Cu" signal "BOTTOM")
		(9 "F.Adhes" user "F.Adhesive")
		(11 "B.Adhes" user "B.Adhesive")
		(13 "F.Paste" user "Package Geometry/Pastemask Top")
		(15 "B.Paste" user "Package Geometry/Pastemask Bottom")
		(5 "F.SilkS" user "Ref Des/Silkscreen Top")
		(7 "B.SilkS" user "Ref Des/Silkscreen Bottom")
		(1 "F.Mask" user "Board Geometry/Soldermask Top")
		(3 "B.Mask" user "Board Geometry/Soldermask Bottom")
		(17 "Dwgs.User" user "User.Drawings")
		(19 "Cmts.User" user "User.Comments")
		(21 "Eco1.User" user "User.Eco1")
		(23 "Eco2.User" user "User.Eco2")
		(25 "Edge.Cuts" user "Board Geometry/Outline")
		(27 "Margin" user)
		(31 "F.CrtYd" user "Package Geometry/Place Bound Top")
		(29 "B.CrtYd" user "Package Geometry/Place Bound Bottom")
		(35 "F.Fab" user "Ref Des/Assembly Top")
		(33 "B.Fab" user "Ref Des/Assembly Bottom")
	)
	(footprint ""
		(layer "F.Cu")
		(at 120.396 -431.038 180)
		(property "Reference" "R3448"
			(at 0 0 180)
			(layer "F.SilkS")
			(hide yes)
			(effects
				(font
					(size 1.27 1.27)
				)
			)
		)
		(property "Value" ""
			(at 0 0 180)
			(layer "F.Fab")
			(effects
				(font
					(size 1.27 1.27)
				)
			)
		)
		(duplicate_pad_numbers_are_jumpers no)
		(fp_line
			(start 0.7874 0.4064)
			(end -0.7874 0.4064)
			(stroke
				(width 0.1524)
				(type default)
			)
			(layer "F.SilkS")
		)
		(fp_line
			(start 0.7874 -0.4064)
			(end 0.7874 0.4064)
			(stroke
				(width 0.1524)
				(type default)
			)
			(layer "F.SilkS")
		)
		(fp_line
			(start -0.7874 0.4064)
			(end -0.7874 -0.4064)
			(stroke
				(width 0.1524)
				(type default)
			)
			(layer "F.SilkS")
		)
		(fp_line
			(start -0.7874 -0.4064)
			(end 0.7874 -0.4064)
			(stroke
				(width 0.1524)
				(type default)
			)
			(layer "F.SilkS")
		)
		(fp_line
			(start 0.67945 0.3048)
			(end 0.120396 0.3048)
			(stroke
				(width 0.1)
				(type default)
			)
			(layer "F.Fab")
		)
		(fp_line
			(start 0.67945 -0.3048)
			(end 0.67945 0.3048)
			(stroke
				(width 0.1)
				(type default)
			)
			(layer "F.Fab")
		)
		(fp_line
			(start 0.12065 -0.2794)
			(end 0.12065 -0.3048)
			(stroke
				(width 0.1)
				(type default)
			)
			(layer "F.Fab")
		)
		(fp_line
			(start 0.12065 -0.3048)
			(end 0.67945 -0.3048)
			(stroke
				(width 0.1)
				(type default)
			)
			(layer "F.Fab")
		)
		(fp_line
			(start 0.120396 0.3048)
			(end 0.120396 0.2794)
			(stroke
				(width 0.1)
				(type default)
			)
			(layer "F.Fab")
		)
		(fp_line
			(start 0.120396 0.2794)
			(end -0.12065 0.2794)
			(stroke
				(width 0.1)
				(type default)
			)
			(layer "F.Fab")
		)
		(fp_line
			(start -0.12065 0.3048)
			(end -0.67945 0.3048)
			(stroke
				(width 0.1)
				(type default)
			)
			(layer "F.Fab")
		)
		(fp_line
			(start -0.12065 0.2794)
			(end -0.12065 0.3048)
			(stroke
				(width 0.1)
				(type default)
			)
			(layer "F.Fab")
		)
		(fp_line
			(start -0.12065 -0.2794)
			(end 0.12065 -0.2794)
			(stroke
				(width 0.1)
				(type default)
			)
			(layer "F.Fab")
		)
		(fp_line
			(start -0.12065 -0.305054)
			(end -0.12065 -0.2794)
			(stroke
				(width 0.1)
				(type default)
			)
			(layer "F.Fab")
		)
		(fp_line
			(start -0.67945 0.3048)
			(end -0.67945 -0.305054)
			(stroke
				(width 0.1)
				(type default)
			)
			(layer "F.Fab")
		)
		(fp_line
			(start -0.67945 -0.305054)
			(end -0.12065 -0.305054)
			(stroke
				(width 0.1)
				(type default)
			)
			(layer "F.Fab")
		)
		(pad "1" smd circle
			(at -0.40005 0 180)
			(size 0 0)
			(layers "F.Cu" "F.Mask" "F.Paste")
			(net "P3V3_AUX")
		)
		(pad "2" smd circle
			(at 0.40005 0 180)
			(size 0 0)
			(layers "F.Cu" "F.Mask" "F.Paste")
			(net "GPU_FPGA_BOOT_EN")
		)
	)
	(footprint ""
		(layer "F.Cu")
		(at 124.058426 -408.517344 -90)
		(property "Reference" "C6700"
			(at 0 0 270)
			(layer "F.SilkS")
			(hide yes)
			(effects
				(font
					(size 1.27 1.27)
				)
			)
		)
		(property "Value" ""
			(at 0 0 270)
			(layer "F.Fab")
			(effects
				(font
					(size 1.27 1.27)
				)
			)
		)
		(duplicate_pad_numbers_are_jumpers no)
		(fp_line
			(start -0.299974 0.150114)
			(end -0.299974 -0.150114)
			(stroke
				(width 0.1)
				(type default)
			)
			(layer "F.Fab")
		)
		(fp_line
			(start 0.299974 0.150114)
			(end -0.299974 0.150114)
			(stroke
				(width 0.1)
				(type default)
			)
			(layer "F.Fab")
		)
		(fp_line
			(start -0.299974 -0.150114)
			(end 0.299974 -0.150114)
			(stroke
				(width 0.1)
				(type default)
			)
			(layer "F.Fab")
		)
		(fp_line
			(start 0.299974 -0.150114)
			(end 0.299974 0.150114)
			(stroke
				(width 0.1)
				(type default)
			)
			(layer "F.Fab")
		)
		(pad "1" smd rect
			(at -0.2667 0 270)
			(size 0.3048 0.381)
			(layers "F.Cu" "F.Mask" "F.Paste")
			(net "P5E_CPU1_P2_TX_BUF_C_DN<3>")
		)
		(pad "2" smd rect
			(at 0.2667 0 270)
			(size 0.3048 0.381)
			(layers "F.Cu" "F.Mask" "F.Paste")
			(net "P5E_CPU1_P2_TX_BUF_DN<3>")
		)
	)
	(footprint ""
		(layer "F.Cu")
		(at 142.893542 -384.66268)
		(property "Reference" "R876"
			(at 0 0 0)
			(layer "F.SilkS")
			(hide yes)
			(effects
				(font
					(size 1.27 1.27)
				)
			)
		)
		(property "Value" ""
			(at 0 0 0)
			(layer "F.Fab")
			(effects
				(font
					(size 1.27 1.27)
				)
			)
		)
		(duplicate_pad_numbers_are_jumpers no)
		(fp_line
			(start -0.32512 -0.175006)
			(end 0.32512 -0.175006)
			(stroke
				(width 0.1)
				(type default)
			)
			(layer "F.Fab")
		)
		(fp_line
			(start -0.32512 0.175006)
			(end -0.32512 -0.175006)
			(stroke
				(width 0.1)
				(type default)
			)
			(layer "F.Fab")
		)
		(fp_line
			(start 0.32512 -0.175006)
			(end 0.32512 0.175006)
			(stroke
				(width 0.1)
				(type default)
			)
			(layer "F.Fab")
		)
		(fp_line
			(start 0.32512 0.175006)
			(end -0.32512 0.175006)
			(stroke
				(width 0.1)
				(type default)
			)
			(layer "F.Fab")
		)
		(pad "1" smd rect
			(at -0.2667 0)
			(size 0.3048 0.381)
			(layers "F.Cu" "F.Mask" "F.Paste")
			(net "GPIO3_RT_CPU1_P2")
		)
		(pad "2" smd rect
			(at 0.2667 0 180)
			(size 0.3048 0.381)
			(layers "F.Cu" "F.Mask" "F.Paste")
			(net "GND")
		)
	)
)
